# BASEBOARD_FAB2 (Tioga Pass) — schematic netlist excerpt (pin names and nets, part order shuffled) for the footprints in the layout excerpt that follows; sources: Cadence DE-HDL packaged netlist, KiCad conversion of Wiwynn_Tioga_Pass_MB.brd

C7P13  CAP  100UF 4V 20% X5R  pkg 0805  page 76 : A = PVCCMCP_CPU1 ; B = GND
R9W33  RES  4.75K 1% CHIP  pkg 0402  page 158 : A = P3V3_STBY ; B = SP1_BMC_HOST_UART_RX
R9T8  RES  0.0 5% CHIP  pkg 0402  page 181 : A = FM_MATED_IN_N ; B = GND

(kicad_pcb
	(version 20260206)
	(generator "pcbnew")
	(generator_version "10.0")
	(general
		(thickness 1.6)
		(legacy_teardrops no)
	)
	(paper "A4")
	(title_block
		(title "Wiwynn_Tioga_Pass_MB.brd")
		(comment 1 "Tioga Pass / footprints 3849-3851 of 4770")
	)
	(layers
		(0 "F.Cu" signal "TOP")
		(4 "In1.Cu" signal "L2GND")
		(6 "In2.Cu" signal "L3")
		(8 "In3.Cu" signal "L4GND")
		(10 "In4.Cu" signal "L5")
		(12 "In5.Cu" signal "L6GND")
		(14 "In6.Cu" signal "L7VCC")
		(16 "In7.Cu" signal "L8VCC")
		(18 "In8.Cu" signal "L9GND")
		(20 "In9.Cu" signal "L10")
		(22 "In10.Cu" signal "L11GND")
		(24 "In11.Cu" signal "L12")
		(26 "In12.Cu" signal "L13GND")
		(2 "B.Cu" signal "BOTTOM")
		(9 "F.Adhes" user "F.Adhesive")
		(11 "B.Adhes" user "B.Adhesive")
		(13 "F.Paste" user "Package Geometry/Pastemask Top")
		(15 "B.Paste" user "Package Geometry/Pastemask Bottom")
		(5 "F.SilkS" user "Ref Des/Silkscreen Top")
		(7 "B.SilkS" user "Ref Des/Silkscreen Bottom")
		(1 "F.Mask" user "Board Geometry/Soldermask Top")
		(3 "B.Mask" user "Board Geometry/Soldermask Bottom")
		(17 "Dwgs.User" user "User.Drawings")
		(19 "Cmts.User" user "User.Comments")
		(21 "Eco1.User" user "User.Eco1")
		(23 "Eco2.User" user "User.Eco2")
		(25 "Edge.Cuts" user "Board Geometry/Outline")
		(27 "Margin" user)
		(31 "F.CrtYd" user "Package Geometry/Place Bound Top")
		(29 "B.CrtYd" user "Package Geometry/Place Bound Bottom")
		(35 "F.Fab" user "Ref Des/Assembly Top")
		(33 "B.Fab" user "Ref Des/Assembly Bottom")
	)
	(footprint ""
		(layer "B.Cu")
		(at 111.836454 -73.51014)
		(property "Reference" "C7P13"
			(at 0 0 0)
			(layer "B.SilkS")
			(hide yes)
			(effects
				(font
					(size 1.27 1.27)
				)
				(justify mirror)
			)
		)
		(property "Value" ""
			(at 0 0 0)
			(layer "B.Fab")
			(effects
				(font
					(size 1.27 1.27)
				)
				(justify mirror)
			)
		)
		(duplicate_pad_numbers_are_jumpers no)
		(fp_poly
			(pts
				(xy 0.7239 -0.2159) (xy -0.7239 -0.2159) (xy -0.7239 1.9939) (xy 0.7239 1.9939)
			)
			(stroke
				(width 0)
				(type default)
			)
			(fill no)
			(layer "B.CrtYd")
		)
		(fp_line
			(start -0.7239 -0.2159)
			(end 0.7239 -0.2159)
			(stroke
				(width 0.1)
				(type default)
			)
			(layer "B.Fab")
		)
		(fp_line
			(start -0.7239 1.9939)
			(end -0.7239 -0.2159)
			(stroke
				(width 0.1)
				(type default)
			)
			(layer "B.Fab")
		)
		(fp_line
			(start 0.7239 -0.2159)
			(end 0.7239 1.9939)
			(stroke
				(width 0.1)
				(type default)
			)
			(layer "B.Fab")
		)
		(fp_line
			(start 0.7239 1.9939)
			(end -0.7239 1.9939)
			(stroke
				(width 0.1)
				(type default)
			)
			(layer "B.Fab")
		)
		(pad "1" smd rect
			(at 0 0 180)
			(size 1.27 1.016)
			(layers "B.Cu" "B.Mask" "B.Paste")
			(net "PVCCMCP_CPU1")
		)
		(pad "2" smd rect
			(at 0 1.778 180)
			(size 1.27 1.016)
			(layers "B.Cu" "B.Mask" "B.Paste")
			(net "GND")
		)
		(zone
			(layer "B.Cu")
			(hatch none 0.5)
			(connect_pads
				(clearance 0)
			)
			(min_thickness 0.25)
			(keepout
				(tracks not_allowed)
				(vias allowed)
				(pads allowed)
				(copperpour not_allowed)
				(footprints allowed)
			)
			(placement
				(enabled no)
				(sheetname "")
			)
			(fill
				(thermal_gap 0.5)
				(thermal_bridge_width 0.5)
				(island_removal_mode 0)
			)
			(polygon
				(pts
					(xy 112.471454 -73.00214) (xy 111.201454 -73.00214) (xy 111.201454 -72.24014) (xy 112.471454 -72.24014)
				)
			)
		)
	)
	(footprint ""
		(layer "B.Cu")
		(at 492.9886 -38.9636)
		(property "Reference" "R9W33"
			(at 0.8382 -0.67818 0)
			(unlocked yes)
			(layer "B.SilkS")
			(effects
				(font
					(size 0.4064 0.254)
					(thickness 0.1524)
				)
				(justify left mirror)
			)
		)
		(property "Value" ""
			(at 0 0 0)
			(layer "B.Fab")
			(effects
				(font
					(size 1.27 1.27)
				)
				(justify mirror)
			)
		)
		(duplicate_pad_numbers_are_jumpers no)
		(fp_poly
			(pts
				(xy 0.2794 -0.1016) (xy -0.2794 -0.1016) (xy -0.2794 0.9906) (xy 0.2794 0.9906)
			)
			(stroke
				(width 0)
				(type default)
			)
			(fill no)
			(layer "B.CrtYd")
		)
		(fp_line
			(start -0.2794 -0.1016)
			(end 0.2794 -0.1016)
			(stroke
				(width 0.1)
				(type default)
			)
			(layer "B.Fab")
		)
		(fp_line
			(start -0.2794 0.9906)
			(end -0.2794 -0.1016)
			(stroke
				(width 0.1)
				(type default)
			)
			(layer "B.Fab")
		)
		(fp_line
			(start 0.2794 -0.1016)
			(end 0.2794 0.9906)
			(stroke
				(width 0.1)
				(type default)
			)
			(layer "B.Fab")
		)
		(fp_line
			(start 0.2794 0.9906)
			(end -0.2794 0.9906)
			(stroke
				(width 0.1)
				(type default)
			)
			(layer "B.Fab")
		)
		(pad "1" smd rect
			(at 0 0 180)
			(size 0.508 0.508)
			(layers "B.Cu" "B.Mask" "B.Paste")
			(net "P3V3_STBY")
		)
		(pad "2" smd rect
			(at 0 0.889 180)
			(size 0.508 0.508)
			(layers "B.Cu" "B.Mask" "B.Paste")
			(net "SP1_BMC_HOST_UART_RX")
		)
		(zone
			(layer "B.Cu")
			(hatch none 0.5)
			(connect_pads
				(clearance 0)
			)
			(min_thickness 0.25)
			(keepout
				(tracks allowed)
				(vias not_allowed)
				(pads allowed)
				(copperpour not_allowed)
				(footprints allowed)
			)
			(placement
				(enabled no)
				(sheetname "")
			)
			(fill
				(thermal_gap 0.5)
				(thermal_bridge_width 0.5)
				(island_removal_mode 0)
			)
			(polygon
				(pts
					(xy 493.2426 -38.7096) (xy 492.7346 -38.7096) (xy 492.7346 -38.3286) (xy 493.2426 -38.3286)
				)
			)
		)
		(zone
			(layer "B.Cu")
			(hatch none 0.5)
			(connect_pads
				(clearance 0)
			)
			(min_thickness 0.25)
			(keepout
				(tracks not_allowed)
				(vias allowed)
				(pads allowed)
				(copperpour not_allowed)
				(footprints allowed)
			)
			(placement
				(enabled no)
				(sheetname "")
			)
			(fill
				(thermal_gap 0.5)
				(thermal_bridge_width 0.5)
				(island_removal_mode 0)
			)
			(polygon
				(pts
					(xy 493.2426 -38.3286) (xy 492.7346 -38.3286) (xy 492.7346 -38.7096) (xy 493.2426 -38.7096)
				)
			)
		)
	)
	(footprint ""
		(layer "B.Cu")
		(at 26.8478 -30.099 180)
		(property "Reference" "R9T8"
			(at 0 0 0)
			(layer "B.SilkS")
			(hide yes)
			(effects
				(font
					(size 1.27 1.27)
				)
				(justify mirror)
			)
		)
		(property "Value" ""
			(at 0 0 0)
			(layer "B.Fab")
			(effects
				(font
					(size 1.27 1.27)
				)
				(justify mirror)
			)
		)
		(duplicate_pad_numbers_are_jumpers no)
		(fp_rect
			(start -0.2794 -0.1016)
			(end 0.2794 0.9906)
			(stroke
				(width 0)
				(type default)
			)
			(fill no)
			(layer "B.CrtYd")
		)
		(fp_line
			(start 0.2794 0.9906)
			(end -0.2794 0.9906)
			(stroke
				(width 0.1)
				(type default)
			)
			(layer "B.Fab")
		)
		(fp_line
			(start 0.2794 -0.1016)
			(end 0.2794 0.9906)
			(stroke
				(width 0.1)
				(type default)
			)
			(layer "B.Fab")
		)
		(fp_line
			(start -0.2794 0.9906)
			(end -0.2794 -0.1016)
			(stroke
				(width 0.1)
				(type default)
			)
			(layer "B.Fab")
		)
		(fp_line
			(start -0.2794 -0.1016)
			(end 0.2794 -0.1016)
			(stroke
				(width 0.1)
				(type default)
			)
			(layer "B.Fab")
		)
		(pad "1" smd rect
			(at 0 0)
			(size 0.508 0.508)
			(layers "B.Cu" "B.Mask" "B.Paste")
			(net "FM_MATED_IN_N")
		)
		(pad "2" smd rect
			(at 0 0.889)
			(size 0.508 0.508)
			(layers "B.Cu" "B.Mask" "B.Paste")
			(net "GND")
		)
		(zone
			(layer "B.Cu")
			(hatch none 0.5)
			(connect_pads
				(clearance 0)
			)
			(min_thickness 0.25)
			(keepout
				(tracks not_allowed)
				(vias allowed)
				(pads allowed)
				(copperpour not_allowed)
				(footprints allowed)
			)
			(placement
				(enabled no)
				(sheetname "")
			)
			(fill
				(thermal_gap 0.5)
				(thermal_bridge_width 0.5)
				(island_removal_mode 0)
			)
			(polygon
				(pts
					(xy 27.1018 -30.353) (xy 27.1018 -30.734) (xy 26.5938 -30.734) (xy 26.5938 -30.353)
				)
			)
		)
		(zone
			(layer "B.Cu")
			(hatch none 0.5)
			(connect_pads
				(clearance 0)
			)
			(min_thickness 0.25)
			(keepout
				(tracks allowed)
				(vias not_allowed)
				(pads allowed)
				(copperpour not_allowed)
				(footprints allowed)
			)
			(placement
				(enabled no)
				(sheetname "")
			)
			(fill
				(thermal_gap 0.5)
				(thermal_bridge_width 0.5)
				(island_removal_mode 0)
			)
			(polygon
				(pts
					(xy 27.1018 -30.353) (xy 27.1018 -30.734) (xy 26.5938 -30.734) (xy 26.5938 -30.353)
				)
			)
		)
	)
)
